G04 ================== begin FILE IDENTIFICATION RECORD ==================*
G04 Layout Name:  15750-1.brd*
G04 Film Name:    L3*
G04 File Format:  Gerber RS274X*
G04 File Origin:  Cadence Allegro 16.5-S056*
G04 Origin Date:  Fri Dec 30 13:21:37 2016*
G04 *
G04 Layer:  VIA CLASS/L3*
G04 Layer:  PIN/L3*
G04 Layer:  ETCH/L3*
G04 Layer:  DRAWING FORMAT/LAYER_L3*
G04 Layer:  DRAWING FORMAT/LAYER_PCB_STORY*
G04 *
G04 Offset:    (0.00 0.00)*
G04 Mirror:    No*
G04 Mode:      Positive*
G04 Rotation:  0*
G04 FullContactRelief:  No*
G04 UndefLineWidth:     6.00*
G04 ================== end FILE IDENTIFICATION RECORD ====================*
%FSLAX35Y35*MOIN*%
%IR0*IPPOS*OFA0.00000B0.00000*MIA0B0*SFA1.00000B1.00000*%
%ADD12C,.02*%
%ADD11C,.022*%
%ADD13C,.056*%
%ADD10C,.156*%
%ADD14C,.006*%
%ADD15C,.00525*%
%ADD16C,.00475*%
%ADD22C,.03204*%
%ADD23C,.08004*%
%ADD21C,.04404*%
%ADD20C,.04604*%
%ADD17C,.08704*%
%ADD18C,.08904*%
%ADD19C,.18004*%
G75*
%LPD*%
G75*
G36*
G01X223819Y1904D02*
G02X217849Y7874I0J5970D01*
G01Y257349D01*
X219000Y258500D01*
X223801D01*
X230798Y251502D01*
Y99172D01*
G02X230340Y98777I-400J0D01*
G03Y94223I-340J-2277D01*
G02X230798Y93828I58J-395D01*
G01Y38002D01*
X232502Y36298D01*
X305498D01*
X307202Y38002D01*
Y58498D01*
X305998Y59702D01*
X303048D01*
G02X302671Y60234I0J400D01*
G03X298796Y62548I-2171J766D01*
G02X298204I-296J269D01*
G03X294200Y61086I-1704J-1548D01*
G02X293800Y60702I-400J16D01*
G01X268626D01*
G02X268367Y61406I0J400D01*
G03X263766Y68692I-2816J3318D01*
G02X263202Y69057I-164J365D01*
G01Y79139D01*
X263368Y79167D01*
G03X264630Y82819I-368J2171D01*
G02Y83357I296J269D01*
G03X264565Y86388I-1630J1481D01*
G02Y86950I284J281D01*
G03X263368Y90671I-1565J1550D01*
G01X263202Y90699D01*
Y94301D01*
X263368Y94329D01*
G03X264486Y98125I-368J2171D01*
G02X264458Y98687I270J295D01*
G03X264377Y101713I-1639J1470D01*
G02X264405Y102304I283J283D01*
G03X263368Y106171I-1405J1696D01*
G01X263202Y106199D01*
Y129362D01*
X263363Y129394D01*
G03Y133912I-443J2259D01*
G01X263201Y133944D01*
Y140200D01*
G02X263807Y140544I400J1D01*
G03Y146384I1744J2920D01*
G02X263202Y146728I-205J343D01*
G01Y169053D01*
G02X263766Y169418I400J0D01*
G03Y177354I1785J3968D01*
G02X263202Y177719I-164J365D01*
G01Y187801D01*
X263368Y187829D01*
G03X264630Y191481I-368J2171D01*
G02Y192019I296J269D01*
G03Y194981I-1630J1481D01*
G02Y195519I296J269D01*
G03X263368Y199171I-1630J1481D01*
G01X263202Y199199D01*
Y202801D01*
X263368Y202829D01*
G03X264416Y206687I-368J2171D01*
G02X264388Y207274I257J306D01*
G03X264448Y210300I-1569J1545D01*
G02X264476Y210866I296J269D01*
G03X263368Y214671I-1476J1634D01*
G01X263202Y214699D01*
Y238116D01*
X263368Y238144D01*
G03Y242486I-368J2171D01*
G01X263202Y242514D01*
Y248862D01*
G02X263807Y249206I400J1D01*
G03Y255046I1744J2920D01*
G02X263202Y255390I-205J343D01*
G01Y286498D01*
X256998Y292702D01*
X253048D01*
G02X252671Y293234I0J400D01*
G03X252048Y295704I-2171J766D01*
G02Y296296I269J296D01*
G03Y299704I-1548J1704D01*
G02Y300296I269J296D01*
G03Y303704I-1548J1704D01*
G02Y304296I269J296D01*
G03X248796Y307548I-1548J1704D01*
G02X248204I-296J269D01*
G03X244796I-1704J-1548D01*
G02X244204I-296J269D01*
G03X240952Y304296I-1704J-1548D01*
G02Y303704I-269J-296D01*
G03Y300296I1548J-1704D01*
G02Y299704I-269J-296D01*
G03Y296296I1548J-1704D01*
G02Y295704I-269J-296D01*
G03X240329Y293234I1548J-1704D01*
G02X239952Y292702I-377J-132D01*
G01X220197D01*
X220147Y292829D01*
G03X215853I-2147J-829D01*
G01X215803Y292702D01*
X178859D01*
G02X178482Y293234I0J400D01*
G03X174140I-2171J766D01*
G02X173763Y292702I-377J-132D01*
G01X165011D01*
G02X164611Y293086I0J400D01*
G03X160011I-2300J-86D01*
G02X159611Y292702I-400J16D01*
G01X150998D01*
X149702Y293998D01*
Y308998D01*
X148498Y310202D01*
X129502D01*
X127798Y308498D01*
Y298545D01*
G03Y298455I2202J-45D01*
G01Y289194D01*
G02X127184Y288857I-400J0D01*
G03Y285143I-1184J-1857D01*
G02X127798Y284806I214J-337D01*
G01Y284592D01*
X127674Y284541D01*
G03Y280459I826J-2041D01*
G01X127798Y280408D01*
Y270502D01*
X128000Y270301D01*
Y268500D01*
X127349Y267849D01*
X7874D01*
G02X1904Y273819I0J5970D01*
G01Y355551D01*
G02X7874Y361521I5970J0D01*
G01X341535D01*
G02X347505Y355551I0J-5970D01*
G01Y279505D01*
X347000Y279000D01*
X338000D01*
X335500Y276500D01*
Y218000D01*
X338000Y215500D01*
X347005D01*
X347505Y215000D01*
Y195925D01*
G02X347441Y195861I-64J0D01*
G01X321062D01*
G03X317190Y191989I1J-3873D01*
G01Y175256D01*
G03X321063Y171383I3873J0D01*
G01X323938D01*
G02X324212Y170691I0J-400D01*
G03X323732Y169587I1032J-1105D01*
G01Y166437D01*
G03X325720Y165002I1512J0D01*
G02X326246Y164623I126J-379D01*
G01Y161952D01*
G02X325720Y161573I-400J0D01*
G03X323732Y160138I-476J-1435D01*
G01Y156988D01*
G03X325720Y155553I1512J0D01*
G02X326246Y155174I126J-379D01*
G01Y152493D01*
G02X325719Y152114I-400J0D01*
G03X323985Y151508I-475J-1425D01*
G01X323973Y151490D01*
X323842Y151359D01*
G02X323500Y151216I-343J340D01*
G01X320160D01*
X318554Y152822D01*
Y169375D01*
G03X317393Y172178I-3966J-1D01*
G01X303677Y185894D01*
G03X300874Y187054I-2802J-2805D01*
G01X286698D01*
X285964Y187787D01*
G02X283465Y193822I6036J6034D01*
G01Y193873D01*
X283464Y193876D01*
Y218225D01*
G03X282162Y221370I-4448J1D01*
G03X279014Y222674I-3147J-3147D01*
G01X277516D01*
X277511Y222870D01*
G03X272688Y222812I-2411J-59D01*
G01Y218372D01*
G03X277510Y218278I2412J0D01*
G01X277517Y218470D01*
X279014D01*
G02X279188Y218398I0J-246D01*
G01X279189Y218397D01*
G02X279260Y218225I-173J-172D01*
G01Y210043D01*
G02X278577Y209761I-400J0D01*
G03X275925Y210864I-2652J-2637D01*
G01X275516D01*
X275511Y211059D01*
G03X270688Y211001I-2411J-59D01*
G01Y206561D01*
G03X274782Y204833I2412J0D01*
G02X275460Y204546I278J-287D01*
G01Y191534D01*
G03X276098Y188342I8330J5D01*
G01X276559Y187234D01*
G03X279314Y183115I11765J4888D01*
G01X290256Y172174D01*
G02X290131Y171523I-283J-283D01*
G03X293023Y168631I869J-2023D01*
G02X293674Y168756I368J-158D01*
G01X306974Y155455D01*
G02X309235Y149998I-5457J-5458D01*
G01Y149947D01*
X309236Y149944D01*
Y112037D01*
G03X309738Y109510I6625J3D01*
G01X310058Y108735D01*
G03X312405Y105219I9998J4133D01*
G01X319472Y98152D01*
G03X323174Y96620I3703J3709D01*
G01X323500D01*
G02X323840Y96478I-1J-481D01*
G01X323944Y96375D01*
G03X325720Y95711I1300J771D01*
G02X326246Y95332I126J-379D01*
G01Y92661D01*
G02X325720Y92282I-400J0D01*
G03X323732Y90847I-476J-1435D01*
G01Y87697D01*
G03X325720Y86262I1512J0D01*
G02X326246Y85883I126J-379D01*
G01Y83212D01*
G02X325720Y82833I-400J0D01*
G03X323995Y82249I-476J-1435D01*
G02X323000Y81926I-994J1368D01*
G01X289283D01*
G02X288919Y81998I-1J949D01*
G02X286915Y83337I2358J5699D01*
G01X285113Y85138D01*
G02X283893Y86964I3981J3981D01*
G01X283612Y87641D01*
G02X283464Y88383I1795J744D01*
G01Y109563D01*
G03X282162Y112708I-4448J1D01*
G03X279014Y114012I-3147J-3147D01*
G01X277515D01*
X277511Y114208D01*
G03X272688Y114150I-2411J-58D01*
G01Y109710D01*
G03X277510Y109616I2412J0D01*
G01X277517Y109808D01*
X279014D01*
G02X279188Y109736I0J-246D01*
G01X279189Y109735D01*
G02X279260Y109563I-173J-172D01*
G01Y101381D01*
G02X278577Y101099I-400J0D01*
G03X275925Y102202I-2652J-2637D01*
G01X275515D01*
X275511Y102397D01*
G03X270688Y102339I-2411J-58D01*
G01Y97899D01*
G03X274782Y96171I2412J0D01*
G02X275460Y95884I278J-287D01*
G01Y94031D01*
G02X274756Y93772I-400J0D01*
G03Y90794I-1756J-1489D01*
G02X275460Y90535I304J-259D01*
G01Y87962D01*
G03X276064Y84928I7928J1D01*
G01X276553Y83748D01*
G03X279313Y79617I11770J4876D01*
G01X281979Y76950D01*
G03X286085Y74207I8940J8937D01*
G03X288329Y73760I2247J5424D01*
G01X300364D01*
X313736Y60389D01*
X313738Y60387D01*
G03X313768Y60356I1067J1003D01*
G03X317470Y58824I3703J3709D01*
G01X323500D01*
G02X323842Y58681I-1J-483D01*
G01X323945Y58579D01*
X323957Y58559D01*
G03X325720Y57916I1288J792D01*
G02X326246Y57537I126J-379D01*
G01Y55582D01*
G02X325753Y55193I-400J0D01*
G03X323581Y51608I-509J-2142D01*
G02Y51345I-151J-132D01*
G03X325753Y47760I1663J-1443D01*
G02X326246Y47371I93J-389D01*
G01Y46004D01*
G02X326181Y45939I-65J0D01*
G01X321062D01*
G03X317190Y42067I1J-3873D01*
G01Y25334D01*
G03X321062Y21462I3873J1D01*
G01X347441D01*
G02X347505Y21398I0J-64D01*
G01Y1968D01*
G02X347441Y1904I-64J0D01*
G01X223819D01*
G37*
G36*
G01X233000Y37500D02*
X232000Y38500D01*
Y65860D01*
G03Y68140I-2000J1140D01*
G01Y69860D01*
G03Y72140I-2000J1140D01*
G01Y73860D01*
G03Y76140I-2000J1140D01*
G01Y95360D01*
G03Y97640I-2000J1140D01*
G01Y120860D01*
G03Y123140I-2000J1140D01*
G01Y124860D01*
G03Y127140I-2000J1140D01*
G01Y128860D01*
G03Y131140I-2000J1140D01*
G01Y133360D01*
G03Y135640I-2000J1140D01*
G01Y137360D01*
G03Y139640I-2000J1140D01*
G01Y141360D01*
G03Y143640I-2000J1140D01*
G01Y174360D01*
G03Y176640I-2000J1140D01*
G01Y178360D01*
G03Y180640I-2000J1140D01*
G01Y182360D01*
G03Y184640I-2000J1140D01*
G01Y229360D01*
G03Y231640I-2000J1140D01*
G01Y233360D01*
G03Y235640I-2000J1140D01*
G01Y237360D01*
G03Y239640I-2000J1140D01*
G01Y241860D01*
G03Y244140I-2000J1140D01*
G01Y245860D01*
G03Y248140I-2000J1140D01*
G01Y249860D01*
G03X230903Y253118I-2000J1140D01*
G01X230867Y253133D01*
X214000Y270000D01*
X130000D01*
X129000Y271000D01*
Y280350D01*
X129142Y280394D01*
G03Y284606I-642J2106D01*
G01X129000Y284650D01*
Y295968D01*
G02X129492Y296357I400J0D01*
G03Y300643I508J2143D01*
G02X129000Y301032I-92J389D01*
G01Y308000D01*
X130000Y309000D01*
X144032D01*
G02X144397Y308437I0J-400D01*
G03X144952Y305796I2103J-937D01*
G02Y305204I-269J-296D01*
G03X147863Y301645I1548J-1704D01*
G02X148500Y301323I237J-322D01*
G01Y293500D01*
X150500Y291500D01*
X160565D01*
G03X164057I1746J1500D01*
G01X215748D01*
X215790Y291356D01*
G03X220210I2210J644D01*
G01X220252Y291500D01*
X256500D01*
X262000Y286000D01*
Y242277D01*
G03Y238353I1000J-1962D01*
G01Y214462D01*
G03X261371Y211019I1000J-1962D01*
G02X261343Y210453I-296J-269D01*
G03X261403Y207132I1476J-1634D01*
G02X261431Y206545I-257J-306D01*
G03X262000Y203038I1569J-1545D01*
G01Y198962D01*
G03X261370Y195519I1000J-1962D01*
G02Y194981I-296J-269D01*
G03Y192019I1630J-1481D01*
G02Y191481I-296J-269D01*
G03X262000Y188038I1630J-1481D01*
G01Y175901D01*
G03Y170871I3551J-2515D01*
G01Y133763D01*
G03Y129543I920J-2110D01*
G01Y105962D01*
G03X261442Y102444I1000J-1962D01*
G02X261414Y101853I-283J-283D01*
G03X261333Y98532I1405J-1696D01*
G02X261361Y97970I-270J-295D01*
G03X262000Y94538I1639J-1470D01*
G01Y90462D01*
G03X261435Y86950I1000J-1962D01*
G02Y86388I-284J-281D01*
G03X261370Y83357I1565J-1550D01*
G02Y82819I-296J-269D01*
G03X262000Y79376I1630J-1481D01*
G01Y67239D01*
G03X265036Y60403I3551J-2515D01*
G01X265105Y60395D01*
X266000Y59500D01*
X294500D01*
X295500Y58500D01*
X305500D01*
X306000Y58000D01*
Y38500D01*
X305000Y37500D01*
X233000D01*
G37*
G36*
G01X313943Y110342D02*
X313623Y111117D01*
G02X313440Y112042I2238J923D01*
G01Y149998D01*
G03X309948Y158429I-11923J0D01*
G01X286207Y182169D01*
G02X286500Y182852I283J283D01*
G03X286597Y182850I130J3963D01*
G01X300774D01*
X314350Y169274D01*
Y152722D01*
G03X315510Y149919I3965J-1D01*
G01X317256Y148173D01*
G03X320059Y147012I2804J2805D01*
G01X323500D01*
G02X323842Y146870I0J-483D01*
G01X323973Y146739D01*
X323985Y146721D01*
G03X325719Y146115I1259J819D01*
G02X326246Y145736I127J-379D01*
G01Y111558D01*
G02X325720Y111179I-400J0D01*
G03X323732Y109744I-476J-1435D01*
G01Y106595D01*
G03X325720Y105160I1512J0D01*
G02X326246Y104781I126J-379D01*
G01Y102110D01*
G02X325720Y101731I-400J0D01*
G03X323957Y101088I-475J-1435D01*
G01X323945Y101068D01*
X323842Y100966D01*
G02X323500Y100824I-342J341D01*
G01X323177D01*
G02X322444Y101127I-1J1036D01*
G01X315379Y108193D01*
G02X313943Y110342I4675J4678D01*
G37*
G36*
G01X316740Y63331D02*
X303267Y76804D01*
G03X303036Y77017I-2802J-2806D01*
G02X303296Y77722I259J305D01*
G01X323001D01*
G02X323993Y77399I-1J-1689D01*
G03X325720Y76813I1251J849D01*
G02X326246Y76434I126J-379D01*
G01Y73763D01*
G02X325720Y73384I-400J0D01*
G03X323732Y71949I-476J-1435D01*
G01Y68799D01*
G03X325720Y67364I1512J0D01*
G02X326246Y66985I126J-379D01*
G01Y64314D01*
G02X325720Y63935I-400J0D01*
G03X323957Y63292I-475J-1435D01*
G01X323945Y63272D01*
X323842Y63170D01*
G02X323500Y63028I-342J341D01*
G01X317473D01*
G02X316740Y63331I-1J1036D01*
G37*
%LPC*%
G75*
G36*
G01X80548Y346296D02*
G03Y345704I269J-296D01*
G02X77452I-1548J-1704D01*
G03Y346296I-269J296D01*
G02X80548I1548J1704D01*
G37*
G36*
G01X220607Y323452D02*
G03X220015I-296J-269D01*
G02Y326548I-1704J1548D01*
G03X220607I296J269D01*
G02Y323452I1704J-1548D01*
G37*
G36*
G01X139975Y323112D02*
G03X139336I-320J-241D01*
G02Y325888I-1836J1388D01*
G03X139975I320J241D01*
G02X143515Y326048I1836J-1388D01*
G03X144107I296J269D01*
G02X147515I1704J-1548D01*
G03X148107I296J269D01*
G02X151515I1704J-1548D01*
G03X152107I296J269D01*
G02X155515I1704J-1548D01*
G03X156107I296J269D01*
G02X159515I1704J-1548D01*
G03X160107I296J269D01*
G02X163515I1704J-1548D01*
G03X164107I296J269D01*
G02X167515I1704J-1548D01*
G03X168107I296J269D01*
G02Y322952I1704J-1548D01*
G03X167515I-296J-269D01*
G02X164107I-1704J1548D01*
G03X163515I-296J-269D01*
G02X160107I-1704J1548D01*
G03X159515I-296J-269D01*
G02X156107I-1704J1548D01*
G03X155515I-296J-269D01*
G02X152107I-1704J1548D01*
G03X151515I-296J-269D01*
G02X148107I-1704J1548D01*
G03X147515I-296J-269D01*
G02X144107I-1704J1548D01*
G03X143515I-296J-269D01*
G02X139975Y323112I-1704J1548D01*
G37*
G36*
G01X114417Y315715D02*
X114458Y315833D01*
X108292Y321998D01*
X106032D01*
G03X105643Y321507I0J-400D01*
G02X104909Y319307I-2143J-507D01*
G03Y318693I255J-307D01*
G02X102091I-1409J-1693D01*
G03Y319307I-255J307D01*
G02X101626Y319843I1409J1692D01*
G03X101003Y319916I-340J-210D01*
G01X95440Y314352D01*
Y309904D01*
X94698Y309162D01*
X94701Y309075D01*
G02X90564Y310049I-2201J-75D01*
G03X90410Y310587I-352J190D01*
G02X90060Y314166I1090J1913D01*
G01Y315838D01*
X101075Y326852D01*
X110303D01*
X119958Y317198D01*
X120045Y317201D01*
G02X121815Y313595I75J-2201D01*
G03X122123Y312940I308J-255D01*
G01X123352D01*
X124998Y314586D01*
Y324466D01*
X117162Y332302D01*
X117075Y332299D01*
G02X115307Y333091I-75J2201D01*
G03X114693I-307J-255D01*
G02X111519Y332870I-1693J1409D01*
G03X110981I-269J-296D01*
G02Y336130I-1481J1630D01*
G03X111519I269J296D01*
G02X114693Y335909I1481J-1630D01*
G03X115307I307J255D01*
G02X118693I1693J-1409D01*
G03X119307I307J255D01*
G02X123201Y334425I1693J-1409D01*
G01X123198Y334338D01*
X129852Y327683D01*
Y312575D01*
X125363Y308086D01*
X109209D01*
X109199Y307895D01*
G02X105370Y309481I-2199J105D01*
G03Y310019I-296J269D01*
G02X108666Y312940I1630J1481D01*
G01X114497D01*
G03X114805Y313595I0J400D01*
G02X114417Y315715I1695J1406D01*
G37*
G36*
G01X202557Y312500D02*
G02Y309500I-1746J-1500D01*
G02X199065I-1746J-1500D01*
G02Y312500I1746J1500D01*
G02Y315500I1746J1500D01*
G02X202557I1746J1500D01*
G02Y312500I-1746J-1500D01*
G37*
G36*
G01X117307Y303591D02*
G03X116693I-307J-255D01*
G02Y306409I-1693J1409D01*
G03X117307I307J255D01*
G02Y303591I1693J-1409D01*
G37*
G36*
G01X73548Y288296D02*
G03Y287704I269J-296D01*
G02X70452I-1548J-1704D01*
G03Y288296I-269J296D01*
G02X73548I1548J1704D01*
G37*
G36*
G01X96378Y282158D02*
X98838Y279698D01*
X98925Y279701D01*
G02X97307Y276091I75J-2201D01*
G03X96693I-307J-255D01*
G02X93019Y278461I-1693J1408D01*
G01X93081Y278589D01*
X91524Y280147D01*
Y293026D01*
G02X90870Y296481I976J1974D01*
G03Y297019I-296J269D01*
G02X94699Y298379I1630J1481D01*
G01X94694Y298290D01*
X96378Y296606D01*
Y282158D01*
G37*
G36*
G01X293312Y198571D02*
Y195274D01*
X293304Y195187D01*
G02X289288Y195361I-2004J174D01*
G01Y198561D01*
G02X293312Y198571I2012J0D01*
G37*
G36*
G01X292130Y152769D02*
G03Y152231I296J-269D01*
G02X288870I-1630J-1481D01*
G03Y152769I-296J269D01*
G02X292130I1630J1481D01*
G37*
G36*
G01X305212Y137053D02*
Y132554D01*
X305205Y132466D01*
G02X300388Y132643I-2405J177D01*
G01Y137043D01*
G02X305212Y137053I2412J0D01*
G37*
G36*
G01X294553Y125426D02*
G03X294050Y125195I-131J-378D01*
G02X292643Y128106I-2050J805D01*
G03X293137Y128357I116J383D01*
G02X294553Y125426I2174J-757D01*
G37*
G36*
G01X302938Y126046D02*
G03X303469Y125878I352J190D01*
G02X302433Y122806I1031J-2058D01*
G03X301909Y122994I-359J-176D01*
G02X302938Y126046I-909J2006D01*
G37*
G36*
G01X297012Y89909D02*
Y86612D01*
X297004Y86525D01*
G02X292988Y86699I-2004J174D01*
G01Y89899D01*
G02X297012Y89909I2012J0D01*
G37*
G36*
G01X173954Y303888D02*
G02X170294Y306609I-1643J1612D01*
G03X169923Y307201I-351J192D01*
G02X168263Y311204I-112J2299D01*
G03Y311796I-269J296D01*
G02X171359I1548J1704D01*
G03Y311204I269J-296D01*
G02X171828Y308391I-1548J-1704D01*
G03X172199Y307799I351J-192D01*
G02X173954Y307112I112J-2299D01*
G03X174525I285J280D01*
G02Y303888I1643J-1612D01*
G03X173954I-286J-280D01*
G37*
G36*
G01X115981Y274870D02*
G02X112482Y275620I-1481J1630D01*
G03X111867Y275773I-366J-160D01*
G02X108807Y276091I-1367J1727D01*
G03X108193I-307J-255D01*
G02X105060Y279166I-1693J1409D01*
G01Y281593D01*
X102260Y284394D01*
Y286680D01*
G03X101574Y286960I-400J0D01*
G02X102202Y288512I-1574J1540D01*
G03X102885Y288232I400J2D01*
G01X105160Y290507D01*
Y294196D01*
X105802Y294838D01*
X105799Y294925D01*
G02X106370Y296481I2201J75D01*
G03Y297019I-296J269D01*
G02X106970Y300446I1630J1481D01*
G03Y301154I-187J354D01*
G02X109030I1030J1946D01*
G03Y300446I187J-354D01*
G02X110201Y298425I-1030J-1946D01*
G01X110198Y298338D01*
X111878Y296658D01*
Y293394D01*
X110014Y291531D01*
Y290556D01*
G03X110735Y290317I400J0D01*
G02Y287683I1765J-1317D01*
G03X110014Y287444I-321J-239D01*
G01Y280021D01*
X110338Y279698D01*
X110425Y279701D01*
G02X112518Y278380I74J-2201D01*
G03X113133Y278227I366J160D01*
G02X115981Y278130I1367J-1727D01*
G03X116519I269J296D01*
G02X119481I1481J-1630D01*
G03X120019I269J296D01*
G02X122752Y278311I1480J-1630D01*
G03X123291Y278388I228J329D01*
G02X123748Y275189I1709J-1388D01*
G03X123209Y275112I-228J-329D01*
G02X120019Y274870I-1709J1388D01*
G03X119481I-269J-296D01*
G02X116519I-1481J1630D01*
G03X115981I-269J-296D01*
G37*
G36*
G01X249296Y243452D02*
G03X248704I-296J-269D01*
G02X245725Y246917I-1704J1548D01*
G03Y247583I-221J333D01*
G02X248704Y251048I1275J1917D01*
G03X249296I296J269D01*
G02X252275Y247583I1704J-1548D01*
G03Y246917I221J-333D01*
G02X249296Y243452I-1275J-1917D01*
G37*
G36*
G01Y230952D02*
G03X248704I-296J-269D01*
G02X245452Y234204I-1704J1548D01*
G03Y234796I-269J296D01*
G02X248704Y238048I1548J1704D01*
G03X249296I296J269D01*
G02X252548Y234796I1704J-1548D01*
G03Y234204I269J-296D01*
G02X249296Y230952I-1548J-1704D01*
G37*
G36*
G01Y175952D02*
G03X248704I-296J-269D01*
G02X245452Y179204I-1704J1548D01*
G03Y179796I-269J296D01*
G02X248704Y183048I1548J1704D01*
G03X249296I296J269D01*
G02X252548Y179796I1704J-1548D01*
G03Y179204I269J-296D01*
G02X249296Y175952I-1548J-1704D01*
G37*
G36*
G01X253093Y162980D02*
G03X253170Y162365I290J-276D01*
G02X250407Y162020I-1170J-1865D01*
G03X250330Y162635I-290J276D01*
G02X253093Y162980I1170J1865D01*
G37*
G36*
G01X253630Y153519D02*
G03Y152981I296J-269D01*
G02X250370I-1630J-1481D01*
G03Y153519I-296J269D01*
G02X253630I1630J1481D01*
G37*
G36*
G01X249296Y134790D02*
G03X248704I-296J-269D01*
G02X245725Y138255I-1704J1548D01*
G03Y138921I-221J333D01*
G02X248704Y142386I1275J1917D01*
G03X249296I296J269D01*
G02X252275Y138921I1704J-1548D01*
G03Y138255I221J-333D01*
G02X249296Y134790I-1275J-1917D01*
G37*
G36*
G01Y122290D02*
G03X248704I-296J-269D01*
G02X245452Y125542I-1704J1548D01*
G03Y126134I-269J296D01*
G02X248704Y129386I1548J1704D01*
G03X249296I296J269D01*
G02X252548Y126134I1704J-1548D01*
G03Y125542I269J-296D01*
G02X249296Y122290I-1548J-1704D01*
G37*
G36*
G01Y67290D02*
G03X248704I-296J-269D01*
G02X245452Y70542I-1704J1548D01*
G03Y71134I-269J296D01*
G02X248704Y74386I1548J1704D01*
G03X249296I296J269D01*
G02X252548Y71134I1704J-1548D01*
G03Y70542I269J-296D01*
G02X249296Y67290I-1548J-1704D01*
G37*
G36*
G01X238630Y153981D02*
G02X235370I-1630J-1481D01*
G03Y154519I-296J269D01*
G02X235487Y157599I1630J1480D01*
G03Y158181I-275J291D01*
G02X235873Y161671I1513J1599D01*
G03Y162359I-205J344D01*
G02X235544Y165902I1127J1891D01*
G03X235467Y166555I-265J300D01*
G02X237956Y166848I1033J1945D01*
G03X238033Y166195I265J-300D01*
G02X238127Y162359I-1033J-1944D01*
G03Y161671I205J-344D01*
G02X238513Y158181I-1127J-1891D01*
G03Y157599I275J-291D01*
G02X238630Y154519I-1513J-1600D01*
G03Y153981I296J-269D01*
G37*
G54D22*
X181061Y297750D03*
X195811Y296000D03*
G54D23*
X302000Y290500D03*
Y300500D03*
Y310500D03*
G54D21*
X100250Y313200D03*
X96750Y328500D03*
X100500Y347289D03*
X121456Y289154D03*
X215064Y316100D03*
X225000Y169500D03*
X268140Y161221D03*
X279000Y166000D03*
X296500Y157500D03*
X140500Y281000D03*
X236805Y146452D03*
X251000Y88500D03*
Y197000D03*
X258750Y168000D03*
G54D20*
X58000Y310689D03*
X160811Y310000D03*
X215811Y300000D03*
X225000Y205000D03*
X295500Y110000D03*
X301711Y245000D03*
X249000Y260000D03*
G54D17*
X311614Y31870D03*
G54D18*
Y185414D03*
G54D19*
X25596Y316176D03*
X237013Y17712D03*
X287407Y345704D03*
%LPD*%
G75*
G54D10*
X25596Y316176D03*
X237013Y17712D03*
X287407Y345704D03*
G54D11*
X10000Y330000D03*
Y345000D03*
Y360000D03*
X40000Y270000D03*
Y285000D03*
Y300000D03*
Y330000D03*
Y345000D03*
X25000Y360000D03*
X40000D03*
X55000Y270000D03*
Y285000D03*
X52500Y325189D03*
Y331189D03*
X55000Y360000D03*
X70000Y270000D03*
X59500Y294189D03*
X64500Y309589D03*
X59500Y299939D03*
X71500Y315689D03*
X67900D03*
X72000Y336689D03*
X70000Y360000D03*
X85000Y270000D03*
X89000Y295189D03*
Y291189D03*
Y287189D03*
Y283189D03*
Y303689D03*
Y299689D03*
X75100Y315689D03*
X89000Y329189D03*
Y333189D03*
X85000Y360000D03*
X100000Y270000D03*
Y360000D03*
X115000D03*
X138500Y299500D03*
X134500Y307500D03*
X138500Y303500D03*
Y307500D03*
X138000Y341500D03*
X130000Y360000D03*
X138000Y345500D03*
X142500Y299500D03*
Y303500D03*
Y307500D03*
X150500Y303500D03*
Y307500D03*
X155000Y301350D03*
X149811Y341500D03*
X141811D03*
X145811D03*
X153811D03*
X145000Y360000D03*
X149811Y345500D03*
X141811D03*
X145811D03*
X153811D03*
X164811Y304000D03*
X165811Y341500D03*
X157811D03*
X161811D03*
X169811D03*
X160000Y360000D03*
X165811Y345500D03*
X169811D03*
X157811D03*
X161811D03*
X185811Y304200D03*
Y310500D03*
X181811D03*
Y318500D03*
X185811Y314500D03*
Y326500D03*
Y322500D03*
Y318500D03*
X181811Y326500D03*
Y322500D03*
Y314500D03*
X184500Y334000D03*
Y338000D03*
X175000Y360000D03*
X189811Y310500D03*
Y318500D03*
Y322500D03*
Y326500D03*
Y314500D03*
X190000Y360000D03*
X205000D03*
X220000D03*
X225000Y35000D03*
Y50000D03*
Y80000D03*
Y65000D03*
X230000Y75000D03*
Y67000D03*
Y71000D03*
X225000Y95000D03*
Y110000D03*
X230000Y126000D03*
Y130000D03*
Y122000D03*
Y138500D03*
Y142500D03*
Y134500D03*
Y175500D03*
Y179500D03*
Y183500D03*
Y243000D03*
Y234500D03*
Y238500D03*
Y230500D03*
Y247000D03*
Y251000D03*
X222911Y287089D03*
X237500Y340000D03*
Y344000D03*
Y336000D03*
X235000Y360000D03*
X255000Y5000D03*
Y35000D03*
X241500Y336000D03*
Y344000D03*
Y340000D03*
X250000Y360000D03*
X270000Y5000D03*
Y35000D03*
X265000Y270000D03*
Y285000D03*
X271500Y294000D03*
X267500D03*
X271500Y306000D03*
Y302000D03*
Y298000D03*
X267500D03*
Y302000D03*
Y306000D03*
X260500Y340000D03*
Y344000D03*
Y336000D03*
X256500D03*
Y344000D03*
Y340000D03*
X265000Y360000D03*
X282500Y5000D03*
X272500Y20000D03*
X285000Y32500D03*
X275500Y63346D03*
X280000Y71614D03*
Y67677D03*
X280169Y126732D03*
Y120826D03*
X275768Y144842D03*
X280169Y138543D03*
Y132637D03*
X280000Y176339D03*
X275500Y172008D03*
X280000Y180276D03*
X280169Y247205D03*
X275768Y253504D03*
X280000Y270000D03*
X275500Y294000D03*
X280000Y285000D03*
X275500Y298000D03*
Y302000D03*
Y306000D03*
X280000Y300000D03*
Y315000D03*
X295000Y5000D03*
X300000Y20000D03*
X299500Y46000D03*
X303500D03*
X300000Y35000D03*
X301500Y49000D03*
X297500D03*
X295500Y52000D03*
X299500D03*
X304565Y61142D03*
Y96142D03*
X304500Y92000D03*
X291500Y97204D03*
X291550Y91299D03*
X291500Y85393D03*
X295500Y100000D03*
X291500Y109960D03*
Y101960D03*
Y114921D03*
X304565Y141142D03*
X295500Y208461D03*
X291500Y210961D03*
Y205866D03*
Y218461D03*
Y223583D03*
Y241299D03*
Y229488D03*
Y235394D03*
X295000Y270000D03*
Y285000D03*
Y300000D03*
Y315000D03*
X315000Y5000D03*
Y20000D03*
Y40000D03*
X313000Y179500D03*
X310000Y225000D03*
Y240000D03*
Y255000D03*
Y270000D03*
Y285000D03*
Y300000D03*
Y315000D03*
Y330000D03*
Y360000D03*
Y345000D03*
X324302Y203977D03*
X325000Y225000D03*
Y240000D03*
Y255000D03*
Y270000D03*
Y285000D03*
Y300000D03*
Y315000D03*
Y330000D03*
Y360000D03*
Y345000D03*
X345000Y5000D03*
Y20000D03*
X340000Y285000D03*
Y300000D03*
Y315000D03*
Y330000D03*
Y360000D03*
Y345000D03*
G54D12*
G01X-176139Y-183003D02*
G02I-12000J0D01*
G01X-181289D02*
G02I-6850J0D01*
G01X-172139D02*
X-204139D01*
G01X-188139Y-199003D02*
Y-167003D01*
G01X-172139Y-199003D02*
Y-279003D01*
G01D02*
X1178561D01*
G01X-172139Y-234503D02*
X1178561D01*
G01X-172139Y-199003D02*
X1178561D01*
G01X16394Y316176D02*
X25596D01*
G01Y306974D02*
Y316176D01*
G01D02*
Y325378D01*
G01Y316176D02*
X34798D01*
G01X237013Y8510D02*
Y17712D01*
G01D02*
Y26914D01*
G01X227811Y17712D02*
X237013D01*
G01D02*
X246215D01*
G01X287407Y336502D02*
Y345704D01*
G01D02*
Y354906D01*
G01X278205Y345704D02*
X287407D01*
G01D02*
X296609D01*
G01X302000Y306298D02*
Y310500D01*
G01D02*
Y314702D01*
G01X297798Y310500D02*
X302000D01*
G01D02*
X306202D01*
G01X391061Y-199003D02*
Y-279003D01*
G01X528561Y-199003D02*
Y-279003D01*
G01X643561Y-199003D02*
Y-279003D01*
G01X811061Y-199003D02*
Y-279003D01*
G01X981061Y-199003D02*
Y-279003D01*
G01X1178561Y-199003D02*
Y-279003D01*
G01X1210561Y-183003D02*
X1178561D01*
G01X1206561D02*
G02I-12000J0D01*
G01X1201411D02*
G02I-6850J0D01*
G01X1194561Y-199003D02*
Y-167003D01*
X103000Y277500D03*
X95000D03*
X99000D03*
X106500D03*
X92500Y295000D03*
Y298500D03*
Y309000D03*
X107000Y311500D03*
Y308000D03*
X96750Y313250D03*
X103750Y313200D03*
X91500Y312500D03*
X100500Y335689D03*
X110500Y277500D03*
X122100Y280750D03*
X108000Y295000D03*
X122000Y301000D03*
X108000Y298500D03*
X120120Y315000D03*
X116500D03*
X117000Y334500D03*
X121000D03*
X124000Y315000D03*
X225000Y160250D03*
Y149250D03*
Y164250D03*
X269650Y97899D03*
X271650Y109710D03*
X269650Y102299D03*
X271650Y114110D03*
X271250Y138750D03*
X267700Y153250D03*
X269650Y210961D03*
Y206561D03*
X271650Y222772D03*
Y218372D03*
X275100Y109710D03*
X273100Y102299D03*
Y97899D03*
X275100Y114110D03*
X278860Y162250D03*
X273500Y194055D03*
Y199961D03*
X273100Y210961D03*
Y206561D03*
X275100Y222772D03*
Y218372D03*
X273600Y240250D03*
X300500Y129100D03*
X299300Y137043D03*
Y132643D03*
X302000Y157500D03*
X292000Y181500D03*
X294750Y195261D03*
Y198661D03*
X325244Y56201D03*
Y62500D03*
Y59351D03*
Y75099D03*
Y65650D03*
Y78248D03*
Y93996D03*
Y84548D03*
Y97146D03*
Y81398D03*
Y112894D03*
Y103445D03*
Y100296D03*
Y128642D03*
Y119193D03*
Y144390D03*
Y138091D03*
Y153839D03*
Y150689D03*
Y147540D03*
Y163288D03*
G54D13*
X302000Y310500D03*
G54D14*
G01X-148956Y-251503D02*
Y-269003D01*
X-140222D01*
G01X-127089Y-257337D02*
Y-269003D01*
G01Y-252670D02*
X-127526Y-252378D01*
Y-251795D01*
X-127089Y-251503D01*
X-126652Y-251795D01*
Y-252378D01*
X-127089Y-252670D01*
G01X-112646Y-273378D02*
X-111117Y-274545D01*
X-109371Y-274836D01*
X-107843Y-274545D01*
X-106532Y-273087D01*
X-105659Y-271045D01*
Y-257337D01*
G01Y-259670D02*
X-106532Y-258503D01*
X-107843Y-257628D01*
X-109371Y-257337D01*
X-111117Y-257920D01*
X-112209Y-259086D01*
X-113083Y-261128D01*
X-113519Y-263170D01*
X-113301Y-264920D01*
X-112427Y-266962D01*
X-111117Y-268420D01*
X-109371Y-269003D01*
X-108061Y-268711D01*
X-106532Y-267545D01*
X-105659Y-266379D01*
G01X-95801Y-269003D02*
Y-251503D01*
G01Y-259961D02*
X-94709Y-258503D01*
X-93617Y-257628D01*
X-91871Y-257337D01*
X-90561Y-257628D01*
X-89032Y-258795D01*
X-88377Y-260545D01*
Y-269003D01*
G01X-74589Y-251503D02*
Y-269003D01*
G01X-77646Y-257337D02*
X-71532D01*
G01X-60801Y-269003D02*
Y-257337D01*
G01Y-260253D02*
X-59927Y-258795D01*
X-58617Y-257628D01*
X-56871Y-257337D01*
X-55343Y-257628D01*
X-54032Y-258795D01*
X-53377Y-260836D01*
Y-269003D01*
G01X-39589Y-257337D02*
Y-269003D01*
G01Y-252670D02*
X-40026Y-252378D01*
Y-251795D01*
X-39589Y-251503D01*
X-39152Y-251795D01*
Y-252378D01*
X-39589Y-252670D01*
G01X-25801Y-269003D02*
Y-257337D01*
G01Y-260253D02*
X-24927Y-258795D01*
X-23617Y-257628D01*
X-21871Y-257337D01*
X-20343Y-257628D01*
X-19032Y-258795D01*
X-18377Y-260836D01*
Y-269003D01*
G01X-7646Y-273378D02*
X-6117Y-274545D01*
X-4371Y-274836D01*
X-2843Y-274545D01*
X-1532Y-273087D01*
X-659Y-271045D01*
Y-257337D01*
G01Y-259670D02*
X-1532Y-258503D01*
X-2843Y-257628D01*
X-4371Y-257337D01*
X-6117Y-257920D01*
X-7209Y-259086D01*
X-8083Y-261128D01*
X-8519Y-263170D01*
X-8301Y-264920D01*
X-7427Y-266962D01*
X-6117Y-268420D01*
X-4371Y-269003D01*
X-3061Y-268711D01*
X-1532Y-267545D01*
X-659Y-266379D01*
G01X26044Y-269003D02*
Y-251503D01*
X31284D01*
X33031Y-252378D01*
X34341Y-254420D01*
X34778Y-256753D01*
X34341Y-259086D01*
X33249Y-260836D01*
X31284Y-261712D01*
X26044D01*
G01X42452Y-251503D02*
X47911Y-269003D01*
X53370Y-251503D01*
G01X65411D02*
Y-269003D01*
G01X60389Y-251503D02*
X70433D01*
G01X94734Y-269003D02*
Y-251503D01*
X100411Y-266086D01*
X106088Y-251503D01*
Y-269003D01*
G01X117911Y-269586D02*
X117474Y-269295D01*
Y-268711D01*
X117911Y-268420D01*
X118348Y-268711D01*
Y-269295D01*
X117911Y-269586D01*
G01X131263Y-254420D02*
X132573Y-252670D01*
X134101Y-251795D01*
X135848Y-251503D01*
X138031Y-252086D01*
X139559Y-253545D01*
X139996Y-255294D01*
X139778Y-257045D01*
X138904Y-258503D01*
X134538Y-261420D01*
X132573Y-263461D01*
X131263Y-266379D01*
X130826Y-269003D01*
X139996D01*
G01X164952D02*
X170411Y-251503D01*
X175870Y-269003D01*
G01X173904Y-262878D02*
X166917D01*
G01X191841Y-251503D02*
Y-269003D01*
G01Y-266379D02*
X190968Y-267837D01*
X189657Y-268711D01*
X188129Y-269003D01*
X186383Y-268420D01*
X185073Y-266962D01*
X184199Y-265212D01*
X183981Y-263170D01*
X184199Y-261128D01*
X185073Y-259378D01*
X186383Y-257920D01*
X188129Y-257337D01*
X189657Y-257628D01*
X190749Y-258212D01*
X191841Y-259378D01*
G01X209341Y-269003D02*
Y-257337D01*
G01Y-259378D02*
X208468Y-258212D01*
X207157Y-257628D01*
X205629Y-257337D01*
X204101Y-257920D01*
X202791Y-259086D01*
X201917Y-260836D01*
X201481Y-263170D01*
X201917Y-265503D01*
X202791Y-267253D01*
X204101Y-268420D01*
X205629Y-269003D01*
X207157Y-268711D01*
X208468Y-267837D01*
X209341Y-266670D01*
G01X218981Y-274836D02*
Y-257337D01*
G01Y-259961D02*
X220073Y-258503D01*
X221164Y-257628D01*
X222911Y-257337D01*
X224439Y-257628D01*
X225968Y-259086D01*
X226623Y-261128D01*
X226841Y-263170D01*
X226623Y-265212D01*
X225968Y-267253D01*
X224657Y-268420D01*
X222911Y-269003D01*
X221383Y-268711D01*
X219854Y-267837D01*
X218981Y-266670D01*
G01X240411Y-251503D02*
Y-269003D01*
G01X237354Y-257337D02*
X243468D01*
G01X257911Y-269003D02*
X256601Y-268711D01*
X255291Y-267545D01*
X254417Y-265503D01*
X253981Y-263170D01*
X254417Y-260836D01*
X255291Y-258795D01*
X256601Y-257628D01*
X257911Y-257337D01*
X259221Y-257628D01*
X260531Y-258795D01*
X261404Y-260836D01*
X261623Y-263170D01*
X261404Y-265503D01*
X260531Y-267545D01*
X259221Y-268711D01*
X257911Y-269003D01*
G01X272354D02*
Y-257337D01*
G01Y-259670D02*
X273446Y-258503D01*
X274538Y-257628D01*
X276066Y-257337D01*
X277157Y-257628D01*
X278468Y-258503D01*
G01X315214Y-252962D02*
X313904Y-252086D01*
X312376Y-251503D01*
X310629D01*
X308664Y-252378D01*
X307136Y-253836D01*
X306044Y-255587D01*
X305171Y-258503D01*
X304952Y-261128D01*
X305389Y-263753D01*
X306044Y-265503D01*
X307354Y-267253D01*
X308883Y-268420D01*
X310411Y-269003D01*
X311939D01*
X313468Y-268420D01*
X314778Y-267545D01*
X315870Y-266379D01*
G01X331841Y-269003D02*
Y-257337D01*
G01Y-259378D02*
X330968Y-258212D01*
X329657Y-257628D01*
X328129Y-257337D01*
X326601Y-257920D01*
X325291Y-259086D01*
X324417Y-260836D01*
X323981Y-263170D01*
X324417Y-265503D01*
X325291Y-267253D01*
X326601Y-268420D01*
X328129Y-269003D01*
X329657Y-268711D01*
X330968Y-267837D01*
X331841Y-266670D01*
G01X342354Y-269003D02*
Y-257337D01*
G01Y-259670D02*
X343446Y-258503D01*
X344538Y-257628D01*
X346066Y-257337D01*
X347157Y-257628D01*
X348468Y-258503D01*
G01X366841Y-251503D02*
Y-269003D01*
G01Y-266379D02*
X365968Y-267837D01*
X364657Y-268711D01*
X363129Y-269003D01*
X361383Y-268420D01*
X360073Y-266962D01*
X359199Y-265212D01*
X358981Y-263170D01*
X359199Y-261128D01*
X360073Y-259378D01*
X361383Y-257920D01*
X363129Y-257337D01*
X364657Y-257628D01*
X365749Y-258212D01*
X366841Y-259378D01*
G01X68484Y-224003D02*
Y-206503D01*
X74161Y-221086D01*
X79838Y-206503D01*
Y-224003D01*
G01X91661D02*
X90351Y-223711D01*
X89041Y-222545D01*
X88167Y-220503D01*
X87731Y-218170D01*
X88167Y-215836D01*
X89041Y-213795D01*
X90351Y-212628D01*
X91661Y-212337D01*
X92971Y-212628D01*
X94281Y-213795D01*
X95154Y-215836D01*
X95373Y-218170D01*
X95154Y-220503D01*
X94281Y-222545D01*
X92971Y-223711D01*
X91661Y-224003D01*
G01X113091Y-206503D02*
Y-224003D01*
G01Y-221379D02*
X112218Y-222837D01*
X110907Y-223711D01*
X109379Y-224003D01*
X107633Y-223420D01*
X106323Y-221962D01*
X105449Y-220212D01*
X105231Y-218170D01*
X105449Y-216128D01*
X106323Y-214378D01*
X107633Y-212920D01*
X109379Y-212337D01*
X110907Y-212628D01*
X111999Y-213212D01*
X113091Y-214378D01*
G01X123386Y-216128D02*
X130373D01*
X129718Y-214086D01*
X128626Y-212920D01*
X127098Y-212337D01*
X125569Y-212628D01*
X124259Y-213503D01*
X123386Y-215545D01*
X122949Y-217295D01*
Y-219045D01*
X123386Y-220795D01*
X124478Y-222545D01*
X125788Y-223711D01*
X127316Y-224003D01*
X128844Y-223420D01*
X130373Y-221670D01*
G01X144161Y-224003D02*
Y-206503D01*
G01X424761Y-269003D02*
Y-251503D01*
X422141Y-255003D01*
G01Y-269003D02*
X427381D01*
G01X437458Y-266379D02*
X438767Y-267837D01*
X440296Y-268711D01*
X442261Y-269003D01*
X444226Y-268420D01*
X445754Y-267253D01*
X446846Y-265212D01*
X447064Y-262878D01*
X446628Y-260545D01*
X445536Y-259086D01*
X444007Y-257920D01*
X442479Y-257628D01*
X440951Y-257920D01*
X438986Y-259086D01*
X439641Y-251503D01*
X445536D01*
G01X459324Y-269003D02*
X459761Y-265212D01*
X460416Y-262003D01*
X461289Y-259086D01*
X462381Y-255878D01*
X464128Y-251503D01*
X455394D01*
G01X472458Y-266379D02*
X473767Y-267837D01*
X475296Y-268711D01*
X477261Y-269003D01*
X479226Y-268420D01*
X480754Y-267253D01*
X481846Y-265212D01*
X482064Y-262878D01*
X481628Y-260545D01*
X480536Y-259086D01*
X479007Y-257920D01*
X477479Y-257628D01*
X475951Y-257920D01*
X473986Y-259086D01*
X474641Y-251503D01*
X480536D01*
G01X494761D02*
X493014Y-252086D01*
X491704Y-253545D01*
X490831Y-255294D01*
X490176Y-257628D01*
X489958Y-260253D01*
X490176Y-262878D01*
X490831Y-265212D01*
X491704Y-266962D01*
X493014Y-268420D01*
X494761Y-269003D01*
X496507Y-268420D01*
X497818Y-266962D01*
X498691Y-265212D01*
X499346Y-262878D01*
X499564Y-260253D01*
X499346Y-257628D01*
X498691Y-255294D01*
X497818Y-253545D01*
X496507Y-252086D01*
X494761Y-251503D01*
G01X411644Y-224003D02*
Y-206503D01*
X416884D01*
X418631Y-207378D01*
X419941Y-209420D01*
X420378Y-211753D01*
X419941Y-214086D01*
X418849Y-215836D01*
X416884Y-216712D01*
X411644D01*
G01X438314Y-207962D02*
X437004Y-207086D01*
X435476Y-206503D01*
X433729D01*
X431764Y-207378D01*
X430236Y-208836D01*
X429144Y-210587D01*
X428271Y-213503D01*
X428052Y-216128D01*
X428489Y-218753D01*
X429144Y-220503D01*
X430454Y-222253D01*
X431983Y-223420D01*
X433511Y-224003D01*
X435039D01*
X436568Y-223420D01*
X437878Y-222545D01*
X438970Y-221379D01*
G01X452757Y-214670D02*
X453631Y-213795D01*
X454286Y-212337D01*
X454723Y-210294D01*
X454286Y-208545D01*
X453413Y-207378D01*
X451884Y-206503D01*
X445989D01*
Y-224003D01*
X453194D01*
X454723Y-222837D01*
X455596Y-221086D01*
X456033Y-219045D01*
X455596Y-217003D01*
X454286Y-215253D01*
X452757Y-214670D01*
X445989D01*
G01X461961Y-229836D02*
X475061D01*
G01X480989Y-224003D02*
Y-206503D01*
X491033Y-224003D01*
Y-206503D01*
G01X503511Y-224003D02*
X501764Y-223711D01*
X500236Y-222545D01*
X498926Y-220795D01*
X498052Y-218753D01*
X497616Y-216420D01*
Y-214086D01*
X498052Y-211753D01*
X498926Y-209711D01*
X500236Y-207962D01*
X501764Y-206795D01*
X503511Y-206503D01*
X505257Y-206795D01*
X506786Y-207962D01*
X508096Y-209711D01*
X508970Y-211753D01*
X509406Y-214086D01*
Y-216420D01*
X508970Y-218753D01*
X508096Y-220795D01*
X506786Y-222545D01*
X505257Y-223711D01*
X503511Y-224003D01*
G01X554352Y-206503D02*
X559811Y-224003D01*
X565270Y-206503D01*
G01X581678Y-224003D02*
X572944D01*
Y-206503D01*
X581678D01*
G01X578184Y-214961D02*
X572944D01*
G01X590444Y-224003D02*
Y-206503D01*
X595903D01*
X597649Y-207378D01*
X598741Y-208545D01*
X599178Y-210878D01*
X598741Y-213212D01*
X597431Y-214670D01*
X595903Y-215545D01*
X590444D01*
G01X595903D02*
X599178Y-224003D01*
G01X612311Y-224586D02*
X611874Y-224295D01*
Y-223711D01*
X612311Y-223420D01*
X612748Y-223711D01*
Y-224295D01*
X612311Y-224586D01*
G01X586061Y-269003D02*
Y-251503D01*
X583441Y-255003D01*
G01Y-269003D02*
X588681D01*
G01X687894Y-206503D02*
Y-224003D01*
X696628D01*
G01X713691D02*
Y-212337D01*
G01Y-214378D02*
X712818Y-213212D01*
X711507Y-212628D01*
X709979Y-212337D01*
X708451Y-212920D01*
X707141Y-214086D01*
X706267Y-215836D01*
X705831Y-218170D01*
X706267Y-220503D01*
X707141Y-222253D01*
X708451Y-223420D01*
X709979Y-224003D01*
X711507Y-223711D01*
X712818Y-222837D01*
X713691Y-221670D01*
G01X722676Y-229253D02*
X723986Y-229836D01*
X725733Y-229253D01*
X726824Y-228087D01*
X727698Y-226628D01*
X729007Y-221962D01*
X731846Y-212337D01*
G01X724859D02*
X729007Y-221962D01*
G01X741486Y-216128D02*
X748473D01*
X747818Y-214086D01*
X746726Y-212920D01*
X745198Y-212337D01*
X743669Y-212628D01*
X742359Y-213503D01*
X741486Y-215545D01*
X741049Y-217295D01*
Y-219045D01*
X741486Y-220795D01*
X742578Y-222545D01*
X743888Y-223711D01*
X745416Y-224003D01*
X746944Y-223420D01*
X748473Y-221670D01*
G01X759204Y-224003D02*
Y-212337D01*
G01Y-214670D02*
X760296Y-213503D01*
X761388Y-212628D01*
X762916Y-212337D01*
X764007Y-212628D01*
X765318Y-213503D01*
G01X714144Y-251503D02*
Y-269003D01*
X722878D01*
G01X731208Y-265503D02*
X732517Y-267545D01*
X734264Y-268711D01*
X736229Y-269003D01*
X737976Y-268711D01*
X739723Y-267253D01*
X740814Y-265503D01*
X741033Y-263753D01*
X740596Y-261712D01*
X739068Y-260253D01*
X737539Y-259670D01*
X735574D01*
G01X737539D02*
X738849Y-258795D01*
X739941Y-257337D01*
X740378Y-255587D01*
X739941Y-253836D01*
X738849Y-252378D01*
X736884Y-251503D01*
X734919Y-251795D01*
X732954Y-252962D01*
G01X830008Y-224003D02*
Y-206503D01*
X834374D01*
X836121Y-207378D01*
X837431Y-208545D01*
X838523Y-210294D01*
X839396Y-212337D01*
X839614Y-215253D01*
X839396Y-218170D01*
X838523Y-220212D01*
X837431Y-221962D01*
X836121Y-223128D01*
X834374Y-224003D01*
X830008D01*
G01X849036Y-216128D02*
X856023D01*
X855368Y-214086D01*
X854276Y-212920D01*
X852748Y-212337D01*
X851219Y-212628D01*
X849909Y-213503D01*
X849036Y-215545D01*
X848599Y-217295D01*
Y-219045D01*
X849036Y-220795D01*
X850128Y-222545D01*
X851438Y-223711D01*
X852966Y-224003D01*
X854494Y-223420D01*
X856023Y-221670D01*
G01X866536Y-221962D02*
X867628Y-223128D01*
X869156Y-224003D01*
X870466D01*
X871776Y-223420D01*
X872649Y-222545D01*
X873086Y-221379D01*
X872868Y-219628D01*
X871994Y-218753D01*
X868064Y-217003D01*
X867191Y-214961D01*
X867628Y-213503D01*
X868501Y-212628D01*
X869811Y-212337D01*
X871121Y-212628D01*
X872431Y-213503D01*
G01X887311Y-212337D02*
Y-224003D01*
G01Y-207670D02*
X886874Y-207378D01*
Y-206795D01*
X887311Y-206503D01*
X887748Y-206795D01*
Y-207378D01*
X887311Y-207670D01*
G01X901754Y-228378D02*
X903283Y-229545D01*
X905029Y-229836D01*
X906557Y-229545D01*
X907868Y-228087D01*
X908741Y-226045D01*
Y-212337D01*
G01Y-214670D02*
X907868Y-213503D01*
X906557Y-212628D01*
X905029Y-212337D01*
X903283Y-212920D01*
X902191Y-214086D01*
X901317Y-216128D01*
X900881Y-218170D01*
X901099Y-219920D01*
X901973Y-221962D01*
X903283Y-223420D01*
X905029Y-224003D01*
X906339Y-223711D01*
X907868Y-222545D01*
X908741Y-221379D01*
G01X918599Y-224003D02*
Y-212337D01*
G01Y-215253D02*
X919473Y-213795D01*
X920783Y-212628D01*
X922529Y-212337D01*
X924057Y-212628D01*
X925368Y-213795D01*
X926023Y-215836D01*
Y-224003D01*
G01X936536Y-216128D02*
X943523D01*
X942868Y-214086D01*
X941776Y-212920D01*
X940248Y-212337D01*
X938719Y-212628D01*
X937409Y-213503D01*
X936536Y-215545D01*
X936099Y-217295D01*
Y-219045D01*
X936536Y-220795D01*
X937628Y-222545D01*
X938938Y-223711D01*
X940466Y-224003D01*
X941994Y-223420D01*
X943523Y-221670D01*
G01X954254Y-224003D02*
Y-212337D01*
G01Y-214670D02*
X955346Y-213503D01*
X956438Y-212628D01*
X957966Y-212337D01*
X959057Y-212628D01*
X960368Y-213503D01*
G01X874194Y-265503D02*
X875286Y-267253D01*
X876596Y-268420D01*
X878124Y-269003D01*
X879871Y-268420D01*
X881181Y-267253D01*
X882491Y-265503D01*
X882928Y-263170D01*
Y-251503D01*
G01X896061Y-269003D02*
X894314Y-268711D01*
X892786Y-267545D01*
X891476Y-265795D01*
X890602Y-263753D01*
X890166Y-261420D01*
Y-259086D01*
X890602Y-256753D01*
X891476Y-254711D01*
X892786Y-252962D01*
X894314Y-251795D01*
X896061Y-251503D01*
X897807Y-251795D01*
X899336Y-252962D01*
X900646Y-254711D01*
X901520Y-256753D01*
X901956Y-259086D01*
Y-261420D01*
X901520Y-263753D01*
X900646Y-265795D01*
X899336Y-267545D01*
X897807Y-268711D01*
X896061Y-269003D01*
G01X913561D02*
Y-261128D01*
X909194Y-251503D01*
G01X917928D02*
X913561Y-261128D01*
G01X1001011Y-269003D02*
Y-251503D01*
X998391Y-255003D01*
G01Y-269003D02*
X1003631D01*
G01X1014363Y-254420D02*
X1015673Y-252670D01*
X1017201Y-251795D01*
X1018948Y-251503D01*
X1021131Y-252086D01*
X1022659Y-253545D01*
X1023096Y-255294D01*
X1022878Y-257045D01*
X1022004Y-258503D01*
X1017638Y-261420D01*
X1015673Y-263461D01*
X1014363Y-266379D01*
X1013926Y-269003D01*
X1023096D01*
G01X1032081Y-269586D02*
X1039941Y-251503D01*
G01X1048708Y-265503D02*
X1050017Y-267545D01*
X1051764Y-268711D01*
X1053729Y-269003D01*
X1055476Y-268711D01*
X1057223Y-267253D01*
X1058314Y-265503D01*
X1058533Y-263753D01*
X1058096Y-261712D01*
X1056568Y-260253D01*
X1055039Y-259670D01*
X1053074D01*
G01X1055039D02*
X1056349Y-258795D01*
X1057441Y-257337D01*
X1057878Y-255587D01*
X1057441Y-253836D01*
X1056349Y-252378D01*
X1054384Y-251503D01*
X1052419Y-251795D01*
X1050454Y-252962D01*
G01X1071011Y-251503D02*
X1069264Y-252086D01*
X1067954Y-253545D01*
X1067081Y-255294D01*
X1066426Y-257628D01*
X1066208Y-260253D01*
X1066426Y-262878D01*
X1067081Y-265212D01*
X1067954Y-266962D01*
X1069264Y-268420D01*
X1071011Y-269003D01*
X1072757Y-268420D01*
X1074068Y-266962D01*
X1074941Y-265212D01*
X1075596Y-262878D01*
X1075814Y-260253D01*
X1075596Y-257628D01*
X1074941Y-255294D01*
X1074068Y-253545D01*
X1072757Y-252086D01*
X1071011Y-251503D01*
G01X1084581Y-269586D02*
X1092441Y-251503D01*
G01X1101863Y-254420D02*
X1103173Y-252670D01*
X1104701Y-251795D01*
X1106448Y-251503D01*
X1108631Y-252086D01*
X1110159Y-253545D01*
X1110596Y-255294D01*
X1110378Y-257045D01*
X1109504Y-258503D01*
X1105138Y-261420D01*
X1103173Y-263461D01*
X1101863Y-266379D01*
X1101426Y-269003D01*
X1110596D01*
G01X1123511Y-251503D02*
X1121764Y-252086D01*
X1120454Y-253545D01*
X1119581Y-255294D01*
X1118926Y-257628D01*
X1118708Y-260253D01*
X1118926Y-262878D01*
X1119581Y-265212D01*
X1120454Y-266962D01*
X1121764Y-268420D01*
X1123511Y-269003D01*
X1125257Y-268420D01*
X1126568Y-266962D01*
X1127441Y-265212D01*
X1128096Y-262878D01*
X1128314Y-260253D01*
X1128096Y-257628D01*
X1127441Y-255294D01*
X1126568Y-253545D01*
X1125257Y-252086D01*
X1123511Y-251503D01*
G01X1141011Y-269003D02*
Y-251503D01*
X1138391Y-255003D01*
G01Y-269003D02*
X1143631D01*
G01X1154363Y-261712D02*
X1155891Y-259670D01*
X1157201Y-258503D01*
X1158948Y-257920D01*
X1160476Y-258503D01*
X1161568Y-259670D01*
X1162441Y-261420D01*
X1162659Y-263461D01*
X1162441Y-265212D01*
X1161568Y-266962D01*
X1160257Y-268420D01*
X1158729Y-269003D01*
X1156983Y-268420D01*
X1155454Y-266670D01*
X1154581Y-264045D01*
X1154363Y-261128D01*
X1154799Y-257337D01*
X1155454Y-255294D01*
X1156546Y-253253D01*
X1158074Y-251795D01*
X1159603Y-251503D01*
X1161131Y-252086D01*
X1162223Y-253545D01*
G01X1048708Y-224003D02*
Y-206503D01*
X1053074D01*
X1054821Y-207378D01*
X1056131Y-208545D01*
X1057223Y-210294D01*
X1058096Y-212337D01*
X1058314Y-215253D01*
X1058096Y-218170D01*
X1057223Y-220212D01*
X1056131Y-221962D01*
X1054821Y-223128D01*
X1053074Y-224003D01*
X1048708D01*
G01X1074941D02*
Y-212337D01*
G01Y-214378D02*
X1074068Y-213212D01*
X1072757Y-212628D01*
X1071229Y-212337D01*
X1069701Y-212920D01*
X1068391Y-214086D01*
X1067517Y-215836D01*
X1067081Y-218170D01*
X1067517Y-220503D01*
X1068391Y-222253D01*
X1069701Y-223420D01*
X1071229Y-224003D01*
X1072757Y-223711D01*
X1074068Y-222837D01*
X1074941Y-221670D01*
G01X1088511Y-206503D02*
Y-224003D01*
G01X1085454Y-212337D02*
X1091568D01*
G01X1102736Y-216128D02*
X1109723D01*
X1109068Y-214086D01*
X1107976Y-212920D01*
X1106448Y-212337D01*
X1104919Y-212628D01*
X1103609Y-213503D01*
X1102736Y-215545D01*
X1102299Y-217295D01*
Y-219045D01*
X1102736Y-220795D01*
X1103828Y-222545D01*
X1105138Y-223711D01*
X1106666Y-224003D01*
X1108194Y-223420D01*
X1109723Y-221670D01*
G54D15*
G01X325244Y62500D02*
X324877Y62134D01*
G02X323500Y61563I-1378J1377D01*
G01X317473D01*
G02X315705Y62295I0J2501D01*
G01X302232Y75768D01*
G03X300464Y76500I-1768J-1769D01*
G01X288330D01*
G02X287133Y76738I0J3131D01*
G02X283917Y78887I3787J9148D01*
G01X281251Y81554D01*
G02X279084Y84797I7071J7071D01*
G01X278595Y85977D01*
G02X278200Y87963I4793J1986D01*
G01Y98462D01*
G03X275925Y100737I-2275J0D01*
G01X275500D01*
G02X274070Y101330I1J2023D01*
G01X273100Y102299D01*
G01X325244Y59351D02*
X324877Y59717D01*
G03X323501Y60288I-1378J-1377D01*
G01X317473D01*
G02X314803Y61392I-2J3777D01*
G01Y61393D01*
X301330Y74866D01*
G03X300464Y75225I-867J-867D01*
G01X288329D01*
G02X286645Y75560I1J4406D01*
G02X283015Y77985I4274J10327D01*
G01X280349Y80652D01*
G02X277906Y84309I7974J7971D01*
G01X277417Y85489D01*
G02X276925Y87963I5971J2473D01*
G01Y98462D01*
G03X275925Y99462I-1000J0D01*
G01X275500D01*
G03X274071Y98870I0J-2021D01*
G01X273100Y97899D01*
G01X325244Y81398D02*
X325231Y81385D01*
G02X323000Y80461I-2231J2231D01*
G01X289282D01*
G02X288359Y80645I1J2414D01*
G02X285879Y82301I2916J7053D01*
G01X284078Y84102D01*
G02X282540Y86403I5016J5017D01*
G01X282259Y87081D01*
G02X282000Y88385I3148J1303D01*
G01Y109563D01*
G03X281126Y111673I-2984J0D01*
G03X279014Y112548I-2112J-2111D01*
G01X277500D01*
G02X276070Y113141I1J2023D01*
G01X275100Y114110D01*
G01X325244Y78248D02*
X325230Y78263D01*
G03X323000Y79186I-2229J-2230D01*
G01X289281D01*
G02X287871Y79467I2J3689D01*
G02X284977Y81399I3403J8231D01*
G01X283176Y83200D01*
G02X281362Y85915I5919J5918D01*
G01X281081Y86593D01*
G02X280725Y88385I4326J1791D01*
G01Y109563D01*
G03X280224Y110771I-1709J-1D01*
G03X279014Y111273I-1211J-1209D01*
G01X277500D01*
G03X276071Y110681I0J-2021D01*
G01X275100Y109710D01*
G01X325244Y97146D02*
X324876Y97514D01*
G03X323500Y98084I-1376J-1376D01*
G01X323177D01*
G02X320507Y99188I-2J3777D01*
G01X313441Y106255D01*
G02X311411Y109295I6614J6615D01*
G01X311091Y110069D01*
G02X310700Y112042I4770J1970D01*
G01Y149999D01*
X310699Y149998D01*
G03X308010Y156491I-9182J1D01*
G01X280350Y184151D01*
G02X277911Y187796I7973J7973D01*
G01X277450Y188904D01*
G02X276925Y191540I6340J2633D01*
G01Y207124D01*
G03X275925Y208124I-1000J0D01*
G01X275500D01*
G03X274071Y207532I0J-2021D01*
G01X273100Y206561D01*
G01X325244Y150689D02*
X324877Y150323D01*
G02X323501Y149752I-1378J1377D01*
G01X320059D01*
G02X319193Y150112I2J1225D01*
G01X317448Y151856D01*
G02X317089Y152722I867J867D01*
G01Y169375D01*
G03X316357Y171143I-2501J0D01*
G01X302642Y184858D01*
G03X300874Y185590I-1768J-1769D01*
G01X286597D01*
G02X285731Y185950I2J1225D01*
G01X284929Y186751D01*
G02X282001Y193822I7071J7070D01*
G01X282000Y193821D01*
Y218225D01*
G03X281126Y220335I-2984J0D01*
G03X279014Y221210I-2112J-2111D01*
G01X277500D01*
G02X276070Y221803I1J2023D01*
G01X275100Y222772D01*
G01X325244Y100296D02*
X324877Y99930D01*
G02X323500Y99359I-1378J1377D01*
G01X323177D01*
G02X321409Y100091I0J2501D01*
G01X314343Y107157D01*
G02X312590Y109783I5713J5712D01*
G01X312270Y110557D01*
G02X311975Y112042I3590J1485D01*
G01Y149998D01*
G03X308912Y157393I-10458J0D01*
G01X281252Y185053D01*
G02X279089Y188286I7071J7071D01*
G01X278628Y189394D01*
G02X278200Y191540I5162J2145D01*
G01Y207124D01*
G03X275925Y209399I-2275J0D01*
G01X275500D01*
G02X274070Y209992I1J2023D01*
G01X273100Y210961D01*
G01X325244Y147540D02*
X324877Y147906D01*
G03X323500Y148477I-1378J-1377D01*
G01X320059D01*
G02X318291Y149209I0J2501D01*
G01X316546Y150954D01*
G02X315814Y152722I1769J1768D01*
G01Y169375D01*
G03X315454Y170241I-1225J-2D01*
G01X301740Y183956D01*
G03X300874Y184315I-867J-867D01*
G01X286597D01*
G02X284829Y185047I0J2501D01*
G01X284027Y185849D01*
G02X280725Y193822I7973J7972D01*
G01Y218225D01*
G03X280224Y219433I-1709J-1D01*
G03X279014Y219935I-1211J-1209D01*
G01X277500D01*
G03X276071Y219343I0J-2021D01*
G01X275100Y218372D01*
G54D16*
G01X92500Y295000D02*
X92963Y294537D01*
Y280743D01*
X95000Y278706D01*
Y277500D01*
G01X99000D02*
X94938Y281562D01*
Y296010D01*
X92500Y298448D01*
Y298500D01*
G01X106500Y277500D02*
Y282189D01*
X103699Y284990D01*
Y287010D01*
X106600Y289911D01*
Y293600D01*
X108000Y295000D01*
G01X116500Y315000D02*
Y315826D01*
X108888Y323438D01*
X102490D01*
X94000Y314948D01*
Y310500D01*
X92500Y309000D01*
G01X91500Y312500D02*
Y315242D01*
X101671Y325413D01*
X109707D01*
X120120Y315000D01*
G01X110500Y277500D02*
X108575Y279425D01*
Y292127D01*
X110438Y293990D01*
Y296062D01*
X108000Y298500D01*
G01X121000Y334500D02*
X128413Y327087D01*
Y313171D01*
X124767Y309525D01*
X108525D01*
X107000Y308000D01*
G01X117000Y334500D02*
X126438Y325062D01*
Y313990D01*
X123948Y311500D01*
X107000D01*
M02*
